# SCM (Grand Teton) — schematic netlist excerpt (pin names and nets, part order shuffled) for the footprints in the layout excerpt that follows; sources: Cadence DE-HDL packaged netlist, KiCad conversion of 12092022_DA0F0TMDCD0_F0T_Management_Board_D_brd_V3_OCP.brd

U49  MC74VHC1G32DTT1G  IC  pkg SOT23-5_0-95_3X1-5  page 54
  IN_B  = PWRGD_P5V_AUX
  IN_A  = PWRGD_P3V3_RGM_R2
  GND  = GND
  OUT_Y  = EN_P1V8
  VCC  = P3V3_LDO

R872  Q_RES  0 5% EMPTY  pkg 0402LF  page 52 : A = PWRGD_P3V3_RGM_R ; B = PWRGD_P3V3_RGM_R3

(kicad_pcb
	(version 20260206)
	(generator "pcbnew")
	(generator_version "10.0")
	(general
		(thickness 1.6)
		(legacy_teardrops no)
	)
	(paper "A4")
	(title_block
		(title "12092022_DA0F0TMDCD0_F0T_Management_Board_D_brd_V3_OCP.brd")
		(comment 1 "Grand Teton / footprints 362-363 of 1440")
	)
	(layers
		(0 "F.Cu" signal "TOP")
		(4 "In1.Cu" signal "GND")
		(6 "In2.Cu" signal "IN1")
		(8 "In3.Cu" signal "GND1")
		(10 "In4.Cu" signal "IN2")
		(12 "In5.Cu" signal "VCC")
		(14 "In6.Cu" signal "VCC1")
		(16 "In7.Cu" signal "IN3")
		(18 "In8.Cu" signal "GND2")
		(20 "In9.Cu" signal "IN4")
		(22 "In10.Cu" signal "GND3")
		(2 "B.Cu" signal "BOTTOM")
		(9 "F.Adhes" user "F.Adhesive")
		(11 "B.Adhes" user "B.Adhesive")
		(13 "F.Paste" user "Package Geometry/Pastemask Top")
		(15 "B.Paste" user "Package Geometry/Pastemask Bottom")
		(5 "F.SilkS" user "Ref Des/Silkscreen Top")
		(7 "B.SilkS" user "Ref Des/Silkscreen Bottom")
		(1 "F.Mask" user "Board Geometry/Soldermask Top")
		(3 "B.Mask" user "Board Geometry/Soldermask Bottom")
		(17 "Dwgs.User" user "User.Drawings")
		(19 "Cmts.User" user "User.Comments")
		(21 "Eco1.User" user "User.Eco1")
		(23 "Eco2.User" user "User.Eco2")
		(25 "Edge.Cuts" user "Board Geometry/Outline")
		(27 "Margin" user)
		(31 "F.CrtYd" user "Package Geometry/Place Bound Top")
		(29 "B.CrtYd" user "Package Geometry/Place Bound Bottom")
		(35 "F.Fab" user "Ref Des/Assembly Top")
		(33 "B.Fab" user "Ref Des/Assembly Bottom")
	)
	(footprint ""
		(layer "F.Cu")
		(at 33.2994 -61.976)
		(property "Reference" "U49"
			(at -2.794 3.55727 0)
			(unlocked yes)
			(layer "F.SilkS")
			(effects
				(font
					(size 0.7874 0.5842)
					(thickness 0.1524)
				)
			)
		)
		(property "Value" ""
			(at 0 0 0)
			(layer "F.Fab")
			(effects
				(font
					(size 1.27 1.27)
				)
			)
		)
		(duplicate_pad_numbers_are_jumpers no)
		(fp_line
			(start -1.834896 -1.575054)
			(end -0.508 -1.575054)
			(stroke
				(width 0.1524)
				(type default)
			)
			(layer "F.SilkS")
		)
		(fp_line
			(start -1.834896 1.575054)
			(end -1.834896 -1.575054)
			(stroke
				(width 0.1524)
				(type default)
			)
			(layer "F.SilkS")
		)
		(fp_line
			(start -0.508 -1.575054)
			(end 0 -1.016)
			(stroke
				(width 0.1524)
				(type default)
			)
			(layer "F.SilkS")
		)
		(fp_line
			(start 0 -1.016)
			(end 0.508 -1.575054)
			(stroke
				(width 0.1524)
				(type default)
			)
			(layer "F.SilkS")
		)
		(fp_line
			(start 0.508 -1.575054)
			(end 1.834896 -1.575054)
			(stroke
				(width 0.1524)
				(type default)
			)
			(layer "F.SilkS")
		)
		(fp_line
			(start 1.834896 -1.575054)
			(end 1.834896 1.575054)
			(stroke
				(width 0.1524)
				(type default)
			)
			(layer "F.SilkS")
		)
		(fp_line
			(start 1.834896 1.575054)
			(end -1.834896 1.575054)
			(stroke
				(width 0.1524)
				(type default)
			)
			(layer "F.SilkS")
		)
		(fp_poly
			(pts
				(xy -3.028696 -1.73736) (xy -3.028696 -0.72136) (xy -2.012696 -1.22936)
			)
			(stroke
				(width 0)
				(type default)
			)
			(fill yes)
			(layer "F.SilkS")
		)
		(fp_line
			(start -0.824992 -1.575054)
			(end 0.824992 -1.575054)
			(stroke
				(width 0.1)
				(type default)
			)
			(layer "F.Fab")
		)
		(fp_line
			(start -0.824992 1.575054)
			(end -0.824992 -1.575054)
			(stroke
				(width 0.1)
				(type default)
			)
			(layer "F.Fab")
		)
		(fp_line
			(start 0.824992 -1.575054)
			(end 0.824992 1.575054)
			(stroke
				(width 0.1)
				(type default)
			)
			(layer "F.Fab")
		)
		(fp_line
			(start 0.824992 1.575054)
			(end -0.824992 1.575054)
			(stroke
				(width 0.1)
				(type default)
			)
			(layer "F.Fab")
		)
		(fp_poly
			(pts
				(xy -3.003296 -1.45796) (xy -3.003296 -0.44196) (xy -1.987296 -0.94996)
			)
			(stroke
				(width 0)
				(type default)
			)
			(fill yes)
			(layer "F.Fab")
		)
		(pad "1" smd rect
			(at -1.199896 -0.94996 270)
			(size 0.7112 1.016)
			(layers "F.Cu" "F.Mask" "F.Paste")
			(net "PWRGD_P5V_AUX")
		)
		(pad "2" smd rect
			(at -1.199896 0 270)
			(size 0.7112 1.016)
			(layers "F.Cu" "F.Mask" "F.Paste")
			(net "PWRGD_P3V3_RGM_R2")
		)
		(pad "3" smd rect
			(at -1.199896 0.94996 270)
			(size 0.7112 1.016)
			(layers "F.Cu" "F.Mask" "F.Paste")
			(net "GND")
		)
		(pad "4" smd rect
			(at 1.199896 0.94996 270)
			(size 0.7112 1.016)
			(layers "F.Cu" "F.Mask" "F.Paste")
			(net "EN_P1V8")
		)
		(pad "5" smd rect
			(at 1.199896 -0.94996 270)
			(size 0.7112 1.016)
			(layers "F.Cu" "F.Mask" "F.Paste")
			(net "P3V3_LDO")
		)
	)
	(footprint ""
		(layer "F.Cu")
		(at 71.4502 -27.9146 -90)
		(property "Reference" "R872"
			(at 0 0 270)
			(layer "F.SilkS")
			(hide yes)
			(effects
				(font
					(size 1.27 1.27)
				)
			)
		)
		(property "Value" ""
			(at 0 0 270)
			(layer "F.Fab")
			(effects
				(font
					(size 1.27 1.27)
				)
			)
		)
		(duplicate_pad_numbers_are_jumpers no)
		(fp_line
			(start -0.7874 0.4064)
			(end -0.7874 -0.4064)
			(stroke
				(width 0.1524)
				(type default)
			)
			(layer "F.SilkS")
		)
		(fp_line
			(start 0.7874 0.4064)
			(end -0.7874 0.4064)
			(stroke
				(width 0.1524)
				(type default)
			)
			(layer "F.SilkS")
		)
		(fp_line
			(start -0.7874 -0.4064)
			(end 0.7874 -0.4064)
			(stroke
				(width 0.1524)
				(type default)
			)
			(layer "F.SilkS")
		)
		(fp_line
			(start 0.7874 -0.4064)
			(end 0.7874 0.4064)
			(stroke
				(width 0.1524)
				(type default)
			)
			(layer "F.SilkS")
		)
		(fp_line
			(start -0.67945 0.3048)
			(end -0.67945 -0.305054)
			(stroke
				(width 0.1)
				(type default)
			)
			(layer "F.Fab")
		)
		(fp_line
			(start -0.12065 0.3048)
			(end -0.67945 0.3048)
			(stroke
				(width 0.1)
				(type default)
			)
			(layer "F.Fab")
		)
		(fp_line
			(start 0.120396 0.3048)
			(end 0.120396 0.2794)
			(stroke
				(width 0.1)
				(type default)
			)
			(layer "F.Fab")
		)
		(fp_line
			(start 0.67945 0.3048)
			(end 0.120396 0.3048)
			(stroke
				(width 0.1)
				(type default)
			)
			(layer "F.Fab")
		)
		(fp_line
			(start -0.12065 0.2794)
			(end -0.12065 0.3048)
			(stroke
				(width 0.1)
				(type default)
			)
			(layer "F.Fab")
		)
		(fp_line
			(start 0.120396 0.2794)
			(end -0.12065 0.2794)
			(stroke
				(width 0.1)
				(type default)
			)
			(layer "F.Fab")
		)
		(fp_line
			(start -0.12065 -0.2794)
			(end 0.12065 -0.2794)
			(stroke
				(width 0.1)
				(type default)
			)
			(layer "F.Fab")
		)
		(fp_line
			(start 0.12065 -0.2794)
			(end 0.12065 -0.3048)
			(stroke
				(width 0.1)
				(type default)
			)
			(layer "F.Fab")
		)
		(fp_line
			(start 0.12065 -0.3048)
			(end 0.67945 -0.3048)
			(stroke
				(width 0.1)
				(type default)
			)
			(layer "F.Fab")
		)
		(fp_line
			(start 0.67945 -0.3048)
			(end 0.67945 0.3048)
			(stroke
				(width 0.1)
				(type default)
			)
			(layer "F.Fab")
		)
		(fp_line
			(start -0.67945 -0.305054)
			(end -0.12065 -0.305054)
			(stroke
				(width 0.1)
				(type default)
			)
			(layer "F.Fab")
		)
		(fp_line
			(start -0.12065 -0.305054)
			(end -0.12065 -0.2794)
			(stroke
				(width 0.1)
				(type default)
			)
			(layer "F.Fab")
		)
		(pad "1" smd circle
			(at -0.40005 0 270)
			(size 0 0)
			(layers "F.Cu" "F.Mask" "F.Paste")
			(net "PWRGD_P3V3_RGM_R")
		)
		(pad "2" smd circle
			(at 0.40005 0 270)
			(size 0 0)
			(layers "F.Cu" "F.Mask" "F.Paste")
			(net "PWRGD_P3V3_RGM_R3")
		)
	)
)
